# S9S_MB_2U (Grand Teton) — schematic netlist excerpt (pin names and nets, part order shuffled) for the footprints in the layout excerpt that follows; sources: Cadence DE-HDL packaged netlist, KiCad conversion of 03242023_DA0F0TMBIJ0_F0T_Motherboard_J_brd_V01_OCP.brd

PR121  Q_RES  0 5% CHIP  pkg 0402LF  page 274 : A = SH_PVCCFA_EHV_CPU0 ; B = SH_PVCCFA_EHV_CPU0_R
R3059  Q_RES  33.2 1% CHIP  pkg 0402LF  page 241 : A = SMB_SML0_3V3AUX_SDA ; B = SMB_SML0_ME_SDA

(kicad_pcb
	(version 20260206)
	(generator "pcbnew")
	(generator_version "10.0")
	(general
		(thickness 1.6)
		(legacy_teardrops no)
	)
	(paper "A4")
	(title_block
		(title "03242023_DA0F0TMBIJ0_F0T_Motherboard_J_brd_V01_OCP.brd")
		(comment 1 "Grand Teton / footprints 102-103 of 6105")
	)
	(layers
		(0 "F.Cu" signal "TOP")
		(4 "In1.Cu" signal "GND")
		(6 "In2.Cu" signal "IN1")
		(8 "In3.Cu" signal "GND1")
		(10 "In4.Cu" signal "IN2")
		(12 "In5.Cu" signal "GND2")
		(14 "In6.Cu" signal "IN3")
		(16 "In7.Cu" signal "GND3")
		(18 "In8.Cu" signal "VCC")
		(20 "In9.Cu" signal "VCC1")
		(22 "In10.Cu" signal "GND4")
		(24 "In11.Cu" signal "IN4")
		(26 "In12.Cu" signal "GND5")
		(28 "In13.Cu" signal "IN5")
		(30 "In14.Cu" signal "GND6")
		(32 "In15.Cu" signal "IN6")
		(34 "In16.Cu" signal "GND7")
		(2 "B.Cu" signal "BOTTOM")
		(9 "F.Adhes" user "F.Adhesive")
		(11 "B.Adhes" user "B.Adhesive")
		(13 "F.Paste" user "Package Geometry/Pastemask Top")
		(15 "B.Paste" user "Package Geometry/Pastemask Bottom")
		(5 "F.SilkS" user "Ref Des/Silkscreen Top")
		(7 "B.SilkS" user "Ref Des/Silkscreen Bottom")
		(1 "F.Mask" user "Board Geometry/Soldermask Top")
		(3 "B.Mask" user "Board Geometry/Soldermask Bottom")
		(17 "Dwgs.User" user "User.Drawings")
		(19 "Cmts.User" user "User.Comments")
		(21 "Eco1.User" user "User.Eco1")
		(23 "Eco2.User" user "User.Eco2")
		(25 "Edge.Cuts" user "Board Geometry/Outline")
		(27 "Margin" user)
		(31 "F.CrtYd" user "Package Geometry/Place Bound Top")
		(29 "B.CrtYd" user "Package Geometry/Place Bound Bottom")
		(35 "F.Fab" user "Ref Des/Assembly Top")
		(33 "B.Fab" user "Ref Des/Assembly Bottom")
	)
	(footprint ""
		(layer "F.Cu")
		(at 9.58088 -59.019948)
		(property "Reference" "R3059"
			(at 0 0 0)
			(layer "F.SilkS")
			(hide yes)
			(effects
				(font
					(size 1.27 1.27)
				)
			)
		)
		(property "Value" ""
			(at 0 0 0)
			(layer "F.Fab")
			(effects
				(font
					(size 1.27 1.27)
				)
			)
		)
		(duplicate_pad_numbers_are_jumpers no)
		(fp_line
			(start -0.7874 -0.4064)
			(end 0.7874 -0.4064)
			(stroke
				(width 0.1524)
				(type default)
			)
			(layer "F.SilkS")
		)
		(fp_line
			(start -0.7874 0.4064)
			(end -0.7874 -0.4064)
			(stroke
				(width 0.1524)
				(type default)
			)
			(layer "F.SilkS")
		)
		(fp_line
			(start 0.7874 -0.4064)
			(end 0.7874 0.4064)
			(stroke
				(width 0.1524)
				(type default)
			)
			(layer "F.SilkS")
		)
		(fp_line
			(start 0.7874 0.4064)
			(end -0.7874 0.4064)
			(stroke
				(width 0.1524)
				(type default)
			)
			(layer "F.SilkS")
		)
		(fp_line
			(start -0.67945 -0.305054)
			(end -0.12065 -0.305054)
			(stroke
				(width 0.1)
				(type default)
			)
			(layer "F.Fab")
		)
		(fp_line
			(start -0.67945 0.3048)
			(end -0.67945 -0.305054)
			(stroke
				(width 0.1)
				(type default)
			)
			(layer "F.Fab")
		)
		(fp_line
			(start -0.12065 -0.305054)
			(end -0.12065 -0.2794)
			(stroke
				(width 0.1)
				(type default)
			)
			(layer "F.Fab")
		)
		(fp_line
			(start -0.12065 -0.2794)
			(end 0.12065 -0.2794)
			(stroke
				(width 0.1)
				(type default)
			)
			(layer "F.Fab")
		)
		(fp_line
			(start -0.12065 0.2794)
			(end -0.12065 0.3048)
			(stroke
				(width 0.1)
				(type default)
			)
			(layer "F.Fab")
		)
		(fp_line
			(start -0.12065 0.3048)
			(end -0.67945 0.3048)
			(stroke
				(width 0.1)
				(type default)
			)
			(layer "F.Fab")
		)
		(fp_line
			(start 0.120396 0.2794)
			(end -0.12065 0.2794)
			(stroke
				(width 0.1)
				(type default)
			)
			(layer "F.Fab")
		)
		(fp_line
			(start 0.120396 0.3048)
			(end 0.120396 0.2794)
			(stroke
				(width 0.1)
				(type default)
			)
			(layer "F.Fab")
		)
		(fp_line
			(start 0.12065 -0.3048)
			(end 0.67945 -0.3048)
			(stroke
				(width 0.1)
				(type default)
			)
			(layer "F.Fab")
		)
		(fp_line
			(start 0.12065 -0.2794)
			(end 0.12065 -0.3048)
			(stroke
				(width 0.1)
				(type default)
			)
			(layer "F.Fab")
		)
		(fp_line
			(start 0.67945 -0.3048)
			(end 0.67945 0.3048)
			(stroke
				(width 0.1)
				(type default)
			)
			(layer "F.Fab")
		)
		(fp_line
			(start 0.67945 0.3048)
			(end 0.120396 0.3048)
			(stroke
				(width 0.1)
				(type default)
			)
			(layer "F.Fab")
		)
		(pad "1" smd circle
			(at -0.40005 0)
			(size 0 0)
			(layers "F.Cu" "F.Mask" "F.Paste")
			(net "SMB_SML0_3V3AUX_SDA")
		)
		(pad "2" smd circle
			(at 0.40005 0)
			(size 0 0)
			(layers "F.Cu" "F.Mask" "F.Paste")
			(net "SMB_SML0_ME_SDA")
		)
	)
	(footprint ""
		(layer "F.Cu")
		(at 421.038528 -140.186156 -90)
		(property "Reference" "PR121"
			(at 0 0 270)
			(layer "F.SilkS")
			(hide yes)
			(effects
				(font
					(size 1.27 1.27)
				)
			)
		)
		(property "Value" ""
			(at 0 0 270)
			(layer "F.Fab")
			(effects
				(font
					(size 1.27 1.27)
				)
			)
		)
		(duplicate_pad_numbers_are_jumpers no)
		(fp_line
			(start -0.7874 0.4064)
			(end -0.7874 -0.4064)
			(stroke
				(width 0.1524)
				(type default)
			)
			(layer "F.SilkS")
		)
		(fp_line
			(start 0.7874 0.4064)
			(end -0.7874 0.4064)
			(stroke
				(width 0.1524)
				(type default)
			)
			(layer "F.SilkS")
		)
		(fp_line
			(start -0.7874 -0.4064)
			(end 0.7874 -0.4064)
			(stroke
				(width 0.1524)
				(type default)
			)
			(layer "F.SilkS")
		)
		(fp_line
			(start 0.7874 -0.4064)
			(end 0.7874 0.4064)
			(stroke
				(width 0.1524)
				(type default)
			)
			(layer "F.SilkS")
		)
		(fp_line
			(start -0.67945 0.3048)
			(end -0.67945 -0.305054)
			(stroke
				(width 0.1)
				(type default)
			)
			(layer "F.Fab")
		)
		(fp_line
			(start -0.12065 0.3048)
			(end -0.67945 0.3048)
			(stroke
				(width 0.1)
				(type default)
			)
			(layer "F.Fab")
		)
		(fp_line
			(start 0.120396 0.3048)
			(end 0.120396 0.2794)
			(stroke
				(width 0.1)
				(type default)
			)
			(layer "F.Fab")
		)
		(fp_line
			(start 0.67945 0.3048)
			(end 0.120396 0.3048)
			(stroke
				(width 0.1)
				(type default)
			)
			(layer "F.Fab")
		)
		(fp_line
			(start -0.12065 0.2794)
			(end -0.12065 0.3048)
			(stroke
				(width 0.1)
				(type default)
			)
			(layer "F.Fab")
		)
		(fp_line
			(start 0.120396 0.2794)
			(end -0.12065 0.2794)
			(stroke
				(width 0.1)
				(type default)
			)
			(layer "F.Fab")
		)
		(fp_line
			(start -0.12065 -0.2794)
			(end 0.12065 -0.2794)
			(stroke
				(width 0.1)
				(type default)
			)
			(layer "F.Fab")
		)
		(fp_line
			(start 0.12065 -0.2794)
			(end 0.12065 -0.3048)
			(stroke
				(width 0.1)
				(type default)
			)
			(layer "F.Fab")
		)
		(fp_line
			(start 0.12065 -0.3048)
			(end 0.67945 -0.3048)
			(stroke
				(width 0.1)
				(type default)
			)
			(layer "F.Fab")
		)
		(fp_line
			(start 0.67945 -0.3048)
			(end 0.67945 0.3048)
			(stroke
				(width 0.1)
				(type default)
			)
			(layer "F.Fab")
		)
		(fp_line
			(start -0.67945 -0.305054)
			(end -0.12065 -0.305054)
			(stroke
				(width 0.1)
				(type default)
			)
			(layer "F.Fab")
		)
		(fp_line
			(start -0.12065 -0.305054)
			(end -0.12065 -0.2794)
			(stroke
				(width 0.1)
				(type default)
			)
			(layer "F.Fab")
		)
		(pad "1" smd circle
			(at -0.40005 0 270)
			(size 0 0)
			(layers "F.Cu" "F.Mask" "F.Paste")
			(net "SH_PVCCFA_EHV_CPU0")
		)
		(pad "2" smd circle
			(at 0.40005 0 270)
			(size 0 0)
			(layers "F.Cu" "F.Mask" "F.Paste")
			(net "SH_PVCCFA_EHV_CPU0_R")
		)
	)
)
